# S9S_MB_2U (Grand Teton) — schematic netlist excerpt (pin names and nets, part order shuffled) for the footprints in the layout excerpt that follows; sources: Cadence DE-HDL packaged netlist, KiCad conversion of 03242023_DA0F0TMBIJ0_F0T_Motherboard_J_brd_V01_OCP.brd

PC295_P0_1  Q_CAP  2.2UF 10V 10% X6S  pkg C0402  page 267 : A = PVCCIN_CPU0_PVCC ; B = GND
R3283  Q_RES  1K 1% EMPTY  pkg 0402LF  page 166 : A = P3V3_AUX ; B = FM_P2E_EQB0

(kicad_pcb
	(version 20260206)
	(generator "pcbnew")
	(generator_version "10.0")
	(general
		(thickness 1.6)
		(legacy_teardrops no)
	)
	(paper "A4")
	(title_block
		(title "03242023_DA0F0TMBIJ0_F0T_Motherboard_J_brd_V01_OCP.brd")
		(comment 1 "Grand Teton / footprints 2536-2537 of 6105")
	)
	(layers
		(0 "F.Cu" signal "TOP")
		(4 "In1.Cu" signal "GND")
		(6 "In2.Cu" signal "IN1")
		(8 "In3.Cu" signal "GND1")
		(10 "In4.Cu" signal "IN2")
		(12 "In5.Cu" signal "GND2")
		(14 "In6.Cu" signal "IN3")
		(16 "In7.Cu" signal "GND3")
		(18 "In8.Cu" signal "VCC")
		(20 "In9.Cu" signal "VCC1")
		(22 "In10.Cu" signal "GND4")
		(24 "In11.Cu" signal "IN4")
		(26 "In12.Cu" signal "GND5")
		(28 "In13.Cu" signal "IN5")
		(30 "In14.Cu" signal "GND6")
		(32 "In15.Cu" signal "IN6")
		(34 "In16.Cu" signal "GND7")
		(2 "B.Cu" signal "BOTTOM")
		(9 "F.Adhes" user "F.Adhesive")
		(11 "B.Adhes" user "B.Adhesive")
		(13 "F.Paste" user "Package Geometry/Pastemask Top")
		(15 "B.Paste" user "Package Geometry/Pastemask Bottom")
		(5 "F.SilkS" user "Ref Des/Silkscreen Top")
		(7 "B.SilkS" user "Ref Des/Silkscreen Bottom")
		(1 "F.Mask" user "Board Geometry/Soldermask Top")
		(3 "B.Mask" user "Board Geometry/Soldermask Bottom")
		(17 "Dwgs.User" user "User.Drawings")
		(19 "Cmts.User" user "User.Comments")
		(21 "Eco1.User" user "User.Eco1")
		(23 "Eco2.User" user "User.Eco2")
		(25 "Edge.Cuts" user "Board Geometry/Outline")
		(27 "Margin" user)
		(31 "F.CrtYd" user "Package Geometry/Place Bound Top")
		(29 "B.CrtYd" user "Package Geometry/Place Bound Bottom")
		(35 "F.Fab" user "Ref Des/Assembly Top")
		(33 "B.Fab" user "Ref Des/Assembly Bottom")
	)
	(footprint ""
		(layer "F.Cu")
		(at 341.339932 -333.525368 -90)
		(property "Reference" "PC295_P0_1"
			(at 0 0 270)
			(layer "F.SilkS")
			(hide yes)
			(effects
				(font
					(size 1.27 1.27)
				)
			)
		)
		(property "Value" ""
			(at 0 0 270)
			(layer "F.Fab")
			(effects
				(font
					(size 1.27 1.27)
				)
			)
		)
		(duplicate_pad_numbers_are_jumpers no)
		(fp_line
			(start -0.7874 0.4064)
			(end -0.7874 -0.4064)
			(stroke
				(width 0.1524)
				(type default)
			)
			(layer "F.SilkS")
		)
		(fp_line
			(start 0.7874 0.4064)
			(end -0.7874 0.4064)
			(stroke
				(width 0.1524)
				(type default)
			)
			(layer "F.SilkS")
		)
		(fp_line
			(start -0.7874 -0.4064)
			(end 0.7874 -0.4064)
			(stroke
				(width 0.1524)
				(type default)
			)
			(layer "F.SilkS")
		)
		(fp_line
			(start 0.7874 -0.4064)
			(end 0.7874 0.4064)
			(stroke
				(width 0.1524)
				(type default)
			)
			(layer "F.SilkS")
		)
		(fp_line
			(start -0.67945 0.3048)
			(end -0.67945 -0.305054)
			(stroke
				(width 0.1)
				(type default)
			)
			(layer "F.Fab")
		)
		(fp_line
			(start -0.12065 0.3048)
			(end -0.67945 0.3048)
			(stroke
				(width 0.1)
				(type default)
			)
			(layer "F.Fab")
		)
		(fp_line
			(start 0.120396 0.3048)
			(end 0.120396 0.2794)
			(stroke
				(width 0.1)
				(type default)
			)
			(layer "F.Fab")
		)
		(fp_line
			(start 0.67945 0.3048)
			(end 0.120396 0.3048)
			(stroke
				(width 0.1)
				(type default)
			)
			(layer "F.Fab")
		)
		(fp_line
			(start -0.12065 0.2794)
			(end -0.12065 0.3048)
			(stroke
				(width 0.1)
				(type default)
			)
			(layer "F.Fab")
		)
		(fp_line
			(start 0.120396 0.2794)
			(end -0.12065 0.2794)
			(stroke
				(width 0.1)
				(type default)
			)
			(layer "F.Fab")
		)
		(fp_line
			(start -0.12065 -0.2794)
			(end 0.12065 -0.2794)
			(stroke
				(width 0.1)
				(type default)
			)
			(layer "F.Fab")
		)
		(fp_line
			(start 0.12065 -0.2794)
			(end 0.12065 -0.3048)
			(stroke
				(width 0.1)
				(type default)
			)
			(layer "F.Fab")
		)
		(fp_line
			(start 0.12065 -0.3048)
			(end 0.67945 -0.3048)
			(stroke
				(width 0.1)
				(type default)
			)
			(layer "F.Fab")
		)
		(fp_line
			(start 0.67945 -0.3048)
			(end 0.67945 0.3048)
			(stroke
				(width 0.1)
				(type default)
			)
			(layer "F.Fab")
		)
		(fp_line
			(start -0.67945 -0.305054)
			(end -0.12065 -0.305054)
			(stroke
				(width 0.1)
				(type default)
			)
			(layer "F.Fab")
		)
		(fp_line
			(start -0.12065 -0.305054)
			(end -0.12065 -0.2794)
			(stroke
				(width 0.1)
				(type default)
			)
			(layer "F.Fab")
		)
		(pad "1" smd circle
			(at -0.40005 0 270)
			(size 0 0)
			(layers "F.Cu" "F.Mask" "F.Paste")
			(net "PVCCIN_CPU0_PVCC")
		)
		(pad "2" smd circle
			(at 0.40005 0 270)
			(size 0 0)
			(layers "F.Cu" "F.Mask" "F.Paste")
			(net "GND")
		)
	)
	(footprint ""
		(layer "F.Cu")
		(at 23.241 -397.025876 -90)
		(property "Reference" "R3283"
			(at 0 0 270)
			(layer "F.SilkS")
			(hide yes)
			(effects
				(font
					(size 1.27 1.27)
				)
			)
		)
		(property "Value" ""
			(at 0 0 270)
			(layer "F.Fab")
			(effects
				(font
					(size 1.27 1.27)
				)
			)
		)
		(duplicate_pad_numbers_are_jumpers no)
		(fp_line
			(start -0.7874 0.4064)
			(end -0.7874 -0.4064)
			(stroke
				(width 0.1524)
				(type default)
			)
			(layer "F.SilkS")
		)
		(fp_line
			(start 0.7874 0.4064)
			(end -0.7874 0.4064)
			(stroke
				(width 0.1524)
				(type default)
			)
			(layer "F.SilkS")
		)
		(fp_line
			(start -0.7874 -0.4064)
			(end 0.7874 -0.4064)
			(stroke
				(width 0.1524)
				(type default)
			)
			(layer "F.SilkS")
		)
		(fp_line
			(start 0.7874 -0.4064)
			(end 0.7874 0.4064)
			(stroke
				(width 0.1524)
				(type default)
			)
			(layer "F.SilkS")
		)
		(fp_line
			(start -0.67945 0.3048)
			(end -0.67945 -0.305054)
			(stroke
				(width 0.1)
				(type default)
			)
			(layer "F.Fab")
		)
		(fp_line
			(start -0.12065 0.3048)
			(end -0.67945 0.3048)
			(stroke
				(width 0.1)
				(type default)
			)
			(layer "F.Fab")
		)
		(fp_line
			(start 0.120396 0.3048)
			(end 0.120396 0.2794)
			(stroke
				(width 0.1)
				(type default)
			)
			(layer "F.Fab")
		)
		(fp_line
			(start 0.67945 0.3048)
			(end 0.120396 0.3048)
			(stroke
				(width 0.1)
				(type default)
			)
			(layer "F.Fab")
		)
		(fp_line
			(start -0.12065 0.2794)
			(end -0.12065 0.3048)
			(stroke
				(width 0.1)
				(type default)
			)
			(layer "F.Fab")
		)
		(fp_line
			(start 0.120396 0.2794)
			(end -0.12065 0.2794)
			(stroke
				(width 0.1)
				(type default)
			)
			(layer "F.Fab")
		)
		(fp_line
			(start -0.12065 -0.2794)
			(end 0.12065 -0.2794)
			(stroke
				(width 0.1)
				(type default)
			)
			(layer "F.Fab")
		)
		(fp_line
			(start 0.12065 -0.2794)
			(end 0.12065 -0.3048)
			(stroke
				(width 0.1)
				(type default)
			)
			(layer "F.Fab")
		)
		(fp_line
			(start 0.12065 -0.3048)
			(end 0.67945 -0.3048)
			(stroke
				(width 0.1)
				(type default)
			)
			(layer "F.Fab")
		)
		(fp_line
			(start 0.67945 -0.3048)
			(end 0.67945 0.3048)
			(stroke
				(width 0.1)
				(type default)
			)
			(layer "F.Fab")
		)
		(fp_line
			(start -0.67945 -0.305054)
			(end -0.12065 -0.305054)
			(stroke
				(width 0.1)
				(type default)
			)
			(layer "F.Fab")
		)
		(fp_line
			(start -0.12065 -0.305054)
			(end -0.12065 -0.2794)
			(stroke
				(width 0.1)
				(type default)
			)
			(layer "F.Fab")
		)
		(pad "1" smd circle
			(at -0.40005 0 270)
			(size 0 0)
			(layers "F.Cu" "F.Mask" "F.Paste")
			(net "P3V3_AUX")
		)
		(pad "2" smd circle
			(at 0.40005 0 270)
			(size 0 0)
			(layers "F.Cu" "F.Mask" "F.Paste")
			(net "FM_P2E_EQB0")
		)
	)
)
